# T6G (Grand Teton) — schematic netlist excerpt (pin names and nets, part order shuffled) for the footprints in the layout excerpt that follows; sources: Cadence DE-HDL packaged netlist, KiCad conversion of 04192023_DAF0TMB3IC0_F0TG_MB_C_brd_V02_OCP.brd

PR3837  Q_RES  17.4K 1% CHIP  pkg 0402LF  page 135 : A = P12V_OCP_IMON_1 ; B = GND
R693  Q_RES  33.2 1% CHIP  pkg 0201LF  page 344 : A = SMB_RT_CPU1_P2_ROM_R_SCL ; B = SMB_RT_CPU1_P2_ROM_SCL
R128  Q_RES  1K 1% EMPTY  pkg 0402LF  page 77 : A = P3V3_AUX ; B = SPI_CPU0_LVC3_SCM_D2

(kicad_pcb
	(version 20260206)
	(generator "pcbnew")
	(generator_version "10.0")
	(general
		(thickness 1.6)
		(legacy_teardrops no)
	)
	(paper "A4")
	(title_block
		(title "04192023_DAF0TMB3IC0_F0TG_MB_C_brd_V02_OCP.brd")
		(comment 1 "Grand Teton / footprints 4283-4285 of 8354")
	)
	(layers
		(0 "F.Cu" signal "TOP")
		(4 "In1.Cu" signal "GND")
		(6 "In2.Cu" signal "IN1")
		(8 "In3.Cu" signal "GND1")
		(10 "In4.Cu" signal "IN2")
		(12 "In5.Cu" signal "GND2")
		(14 "In6.Cu" signal "IN3")
		(16 "In7.Cu" signal "GND3")
		(18 "In8.Cu" signal "VCC")
		(20 "In9.Cu" signal "VCC1")
		(22 "In10.Cu" signal "GND4")
		(24 "In11.Cu" signal "IN4")
		(26 "In12.Cu" signal "GND5")
		(28 "In13.Cu" signal "IN5")
		(30 "In14.Cu" signal "GND6")
		(32 "In15.Cu" signal "IN6")
		(34 "In16.Cu" signal "GND7")
		(2 "B.Cu" signal "BOTTOM")
		(9 "F.Adhes" user "F.Adhesive")
		(11 "B.Adhes" user "B.Adhesive")
		(13 "F.Paste" user "Package Geometry/Pastemask Top")
		(15 "B.Paste" user "Package Geometry/Pastemask Bottom")
		(5 "F.SilkS" user "Ref Des/Silkscreen Top")
		(7 "B.SilkS" user "Ref Des/Silkscreen Bottom")
		(1 "F.Mask" user "Board Geometry/Soldermask Top")
		(3 "B.Mask" user "Board Geometry/Soldermask Bottom")
		(17 "Dwgs.User" user "User.Drawings")
		(19 "Cmts.User" user "User.Comments")
		(21 "Eco1.User" user "User.Eco1")
		(23 "Eco2.User" user "User.Eco2")
		(25 "Edge.Cuts" user "Board Geometry/Outline")
		(27 "Margin" user)
		(31 "F.CrtYd" user "Package Geometry/Place Bound Top")
		(29 "B.CrtYd" user "Package Geometry/Place Bound Bottom")
		(35 "F.Fab" user "Ref Des/Assembly Top")
		(33 "B.Fab" user "Ref Des/Assembly Bottom")
	)
	(footprint ""
		(layer "F.Cu")
		(at 255.780794 -140.118846 -90)
		(property "Reference" "R128"
			(at 0 0 270)
			(layer "F.SilkS")
			(hide yes)
			(effects
				(font
					(size 1.27 1.27)
				)
			)
		)
		(property "Value" ""
			(at 0 0 270)
			(layer "F.Fab")
			(effects
				(font
					(size 1.27 1.27)
				)
			)
		)
		(duplicate_pad_numbers_are_jumpers no)
		(fp_line
			(start -0.7874 0.4064)
			(end -0.7874 -0.4064)
			(stroke
				(width 0.1524)
				(type default)
			)
			(layer "F.SilkS")
		)
		(fp_line
			(start 0.7874 0.4064)
			(end -0.7874 0.4064)
			(stroke
				(width 0.1524)
				(type default)
			)
			(layer "F.SilkS")
		)
		(fp_line
			(start -0.7874 -0.4064)
			(end 0.7874 -0.4064)
			(stroke
				(width 0.1524)
				(type default)
			)
			(layer "F.SilkS")
		)
		(fp_line
			(start 0.7874 -0.4064)
			(end 0.7874 0.4064)
			(stroke
				(width 0.1524)
				(type default)
			)
			(layer "F.SilkS")
		)
		(fp_line
			(start -0.67945 0.3048)
			(end -0.67945 -0.305054)
			(stroke
				(width 0.1)
				(type default)
			)
			(layer "F.Fab")
		)
		(fp_line
			(start -0.12065 0.3048)
			(end -0.67945 0.3048)
			(stroke
				(width 0.1)
				(type default)
			)
			(layer "F.Fab")
		)
		(fp_line
			(start 0.120396 0.3048)
			(end 0.120396 0.2794)
			(stroke
				(width 0.1)
				(type default)
			)
			(layer "F.Fab")
		)
		(fp_line
			(start 0.67945 0.3048)
			(end 0.120396 0.3048)
			(stroke
				(width 0.1)
				(type default)
			)
			(layer "F.Fab")
		)
		(fp_line
			(start -0.12065 0.2794)
			(end -0.12065 0.3048)
			(stroke
				(width 0.1)
				(type default)
			)
			(layer "F.Fab")
		)
		(fp_line
			(start 0.120396 0.2794)
			(end -0.12065 0.2794)
			(stroke
				(width 0.1)
				(type default)
			)
			(layer "F.Fab")
		)
		(fp_line
			(start -0.12065 -0.2794)
			(end 0.12065 -0.2794)
			(stroke
				(width 0.1)
				(type default)
			)
			(layer "F.Fab")
		)
		(fp_line
			(start 0.12065 -0.2794)
			(end 0.12065 -0.3048)
			(stroke
				(width 0.1)
				(type default)
			)
			(layer "F.Fab")
		)
		(fp_line
			(start 0.12065 -0.3048)
			(end 0.67945 -0.3048)
			(stroke
				(width 0.1)
				(type default)
			)
			(layer "F.Fab")
		)
		(fp_line
			(start 0.67945 -0.3048)
			(end 0.67945 0.3048)
			(stroke
				(width 0.1)
				(type default)
			)
			(layer "F.Fab")
		)
		(fp_line
			(start -0.67945 -0.305054)
			(end -0.12065 -0.305054)
			(stroke
				(width 0.1)
				(type default)
			)
			(layer "F.Fab")
		)
		(fp_line
			(start -0.12065 -0.305054)
			(end -0.12065 -0.2794)
			(stroke
				(width 0.1)
				(type default)
			)
			(layer "F.Fab")
		)
		(pad "1" smd circle
			(at -0.40005 0 270)
			(size 0 0)
			(layers "F.Cu" "F.Mask" "F.Paste")
			(net "P3V3_AUX")
		)
		(pad "2" smd circle
			(at 0.40005 0 270)
			(size 0 0)
			(layers "F.Cu" "F.Mask" "F.Paste")
			(net "SPI_CPU0_LVC3_SCM_D2")
		)
	)
	(footprint ""
		(layer "F.Cu")
		(at 163.715446 -419.0492 90)
		(property "Reference" "R693"
			(at 0 0 90)
			(layer "F.SilkS")
			(hide yes)
			(effects
				(font
					(size 1.27 1.27)
				)
			)
		)
		(property "Value" ""
			(at 0 0 90)
			(layer "F.Fab")
			(effects
				(font
					(size 1.27 1.27)
				)
			)
		)
		(duplicate_pad_numbers_are_jumpers no)
		(fp_line
			(start 0.32512 -0.175006)
			(end 0.32512 0.175006)
			(stroke
				(width 0.1)
				(type default)
			)
			(layer "F.Fab")
		)
		(fp_line
			(start -0.32512 -0.175006)
			(end 0.32512 -0.175006)
			(stroke
				(width 0.1)
				(type default)
			)
			(layer "F.Fab")
		)
		(fp_line
			(start 0.32512 0.175006)
			(end -0.32512 0.175006)
			(stroke
				(width 0.1)
				(type default)
			)
			(layer "F.Fab")
		)
		(fp_line
			(start -0.32512 0.175006)
			(end -0.32512 -0.175006)
			(stroke
				(width 0.1)
				(type default)
			)
			(layer "F.Fab")
		)
		(pad "1" smd rect
			(at -0.2667 0 90)
			(size 0.3048 0.381)
			(layers "F.Cu" "F.Mask" "F.Paste")
			(net "SMB_RT_CPU1_P2_ROM_R_SCL")
		)
		(pad "2" smd rect
			(at 0.2667 0 270)
			(size 0.3048 0.381)
			(layers "F.Cu" "F.Mask" "F.Paste")
			(net "SMB_RT_CPU1_P2_ROM_SCL")
		)
	)
	(footprint ""
		(layer "F.Cu")
		(at 438.256172 -32.173418 90)
		(property "Reference" "PR3837"
			(at 0 0 90)
			(layer "F.SilkS")
			(hide yes)
			(effects
				(font
					(size 1.27 1.27)
				)
			)
		)
		(property "Value" ""
			(at 0 0 90)
			(layer "F.Fab")
			(effects
				(font
					(size 1.27 1.27)
				)
			)
		)
		(duplicate_pad_numbers_are_jumpers no)
		(fp_line
			(start 0.7874 -0.4064)
			(end 0.7874 0.4064)
			(stroke
				(width 0.1524)
				(type default)
			)
			(layer "F.SilkS")
		)
		(fp_line
			(start -0.7874 -0.4064)
			(end 0.7874 -0.4064)
			(stroke
				(width 0.1524)
				(type default)
			)
			(layer "F.SilkS")
		)
		(fp_line
			(start 0.7874 0.4064)
			(end -0.7874 0.4064)
			(stroke
				(width 0.1524)
				(type default)
			)
			(layer "F.SilkS")
		)
		(fp_line
			(start -0.7874 0.4064)
			(end -0.7874 -0.4064)
			(stroke
				(width 0.1524)
				(type default)
			)
			(layer "F.SilkS")
		)
		(fp_line
			(start -0.12065 -0.305054)
			(end -0.12065 -0.2794)
			(stroke
				(width 0.1)
				(type default)
			)
			(layer "F.Fab")
		)
		(fp_line
			(start -0.67945 -0.305054)
			(end -0.12065 -0.305054)
			(stroke
				(width 0.1)
				(type default)
			)
			(layer "F.Fab")
		)
		(fp_line
			(start 0.67945 -0.3048)
			(end 0.67945 0.3048)
			(stroke
				(width 0.1)
				(type default)
			)
			(layer "F.Fab")
		)
		(fp_line
			(start 0.12065 -0.3048)
			(end 0.67945 -0.3048)
			(stroke
				(width 0.1)
				(type default)
			)
			(layer "F.Fab")
		)
		(fp_line
			(start 0.12065 -0.2794)
			(end 0.12065 -0.3048)
			(stroke
				(width 0.1)
				(type default)
			)
			(layer "F.Fab")
		)
		(fp_line
			(start -0.12065 -0.2794)
			(end 0.12065 -0.2794)
			(stroke
				(width 0.1)
				(type default)
			)
			(layer "F.Fab")
		)
		(fp_line
			(start 0.120396 0.2794)
			(end -0.12065 0.2794)
			(stroke
				(width 0.1)
				(type default)
			)
			(layer "F.Fab")
		)
		(fp_line
			(start -0.12065 0.2794)
			(end -0.12065 0.3048)
			(stroke
				(width 0.1)
				(type default)
			)
			(layer "F.Fab")
		)
		(fp_line
			(start 0.67945 0.3048)
			(end 0.120396 0.3048)
			(stroke
				(width 0.1)
				(type default)
			)
			(layer "F.Fab")
		)
		(fp_line
			(start 0.120396 0.3048)
			(end 0.120396 0.2794)
			(stroke
				(width 0.1)
				(type default)
			)
			(layer "F.Fab")
		)
		(fp_line
			(start -0.12065 0.3048)
			(end -0.67945 0.3048)
			(stroke
				(width 0.1)
				(type default)
			)
			(layer "F.Fab")
		)
		(fp_line
			(start -0.67945 0.3048)
			(end -0.67945 -0.305054)
			(stroke
				(width 0.1)
				(type default)
			)
			(layer "F.Fab")
		)
		(pad "1" smd circle
			(at -0.40005 0 90)
			(size 0 0)
			(layers "F.Cu" "F.Mask" "F.Paste")
			(net "P12V_OCP_IMON_1")
		)
		(pad "2" smd circle
			(at 0.40005 0 90)
			(size 0 0)
			(layers "F.Cu" "F.Mask" "F.Paste")
			(net "GND")
		)
	)
)
